# T6G (Grand Teton) — schematic netlist excerpt (pin names and nets, part order shuffled) for the footprints in the layout excerpt that follows; sources: Cadence DE-HDL packaged netlist, KiCad conversion of 04192023_DAF0TMB3IC0_F0TG_MB_C_brd_V02_OCP.brd

SW1  SW20S_DHNF10FQTR  SW20S_DHNF-10F-Q-T/R MECH  pkg SW20S_DHNF10FTVTR  page 167
  \1\  = GND
  \2\  = FM_FORCE_ALL_PWRON_ON
  \3\  = GND
  \4\  = PU_BIOS_USB_RECOVERY
  \5\  = PU_FPGA_DEBUG_SW_SPARE
  \6\  = PD_BIOS_DEBUG_MODE
  \7\  = PRSNT_CPU0_N
  \8\  = PRSNT_CPU1_N
  \9\  = GND
  \10\  = PU_FPGA_DEBUG_LED_CTRL
  \11\  = FM_SPD_CPU0_SWITCH_CTRL_N
  \12\  = FM_FORCE_ALL_PWRON
  \13\  = BMC_JTAG_SEL
  \14\  = FM_BIOS_USB_RECOVERY
  \15\  = FPGA_DEBUG_SW_SPARE
  \16\  = BIOS_DEBUG_MODE
  \17\  = FM_PRSNT_CPU0_N
  \18\  = FM_PRSNT_CPU1_N
  \19\  = FM_PASSWORD_CLEAR_N
  \20\  = FPGA_DEBUG_LED_CTRL

(kicad_pcb
	(version 20260206)
	(generator "pcbnew")
	(generator_version "10.0")
	(general
		(thickness 1.6)
		(legacy_teardrops no)
	)
	(paper "A4")
	(title_block
		(title "04192023_DAF0TMB3IC0_F0TG_MB_C_brd_V02_OCP.brd")
		(comment 1 "Grand Teton / footprint 2109 of 8354 (SW1), pads 1-20 of 20")
	)
	(layers
		(0 "F.Cu" signal "TOP")
		(4 "In1.Cu" signal "GND")
		(6 "In2.Cu" signal "IN1")
		(8 "In3.Cu" signal "GND1")
		(10 "In4.Cu" signal "IN2")
		(12 "In5.Cu" signal "GND2")
		(14 "In6.Cu" signal "IN3")
		(16 "In7.Cu" signal "GND3")
		(18 "In8.Cu" signal "VCC")
		(20 "In9.Cu" signal "VCC1")
		(22 "In10.Cu" signal "GND4")
		(24 "In11.Cu" signal "IN4")
		(26 "In12.Cu" signal "GND5")
		(28 "In13.Cu" signal "IN5")
		(30 "In14.Cu" signal "GND6")
		(32 "In15.Cu" signal "IN6")
		(34 "In16.Cu" signal "GND7")
		(2 "B.Cu" signal "BOTTOM")
		(9 "F.Adhes" user "F.Adhesive")
		(11 "B.Adhes" user "B.Adhesive")
		(13 "F.Paste" user "Package Geometry/Pastemask Top")
		(15 "B.Paste" user "Package Geometry/Pastemask Bottom")
		(5 "F.SilkS" user "Ref Des/Silkscreen Top")
		(7 "B.SilkS" user "Ref Des/Silkscreen Bottom")
		(1 "F.Mask" user "Board Geometry/Soldermask Top")
		(3 "B.Mask" user "Board Geometry/Soldermask Bottom")
		(17 "Dwgs.User" user "User.Drawings")
		(19 "Cmts.User" user "User.Comments")
		(21 "Eco1.User" user "User.Eco1")
		(23 "Eco2.User" user "User.Eco2")
		(25 "Edge.Cuts" user "Board Geometry/Outline")
		(27 "Margin" user)
		(31 "F.CrtYd" user "Package Geometry/Place Bound Top")
		(29 "B.CrtYd" user "Package Geometry/Place Bound Bottom")
		(35 "F.Fab" user "Ref Des/Assembly Top")
		(33 "B.Fab" user "Ref Des/Assembly Bottom")
	)
	(footprint ""
		(layer "F.Cu")
		(at 427.7614 -36.642548)
		(property "Reference" "SW1"
			(at -2.2733 -7.534148 0)
			(unlocked yes)
			(layer "F.SilkS")
			(effects
				(font
					(size 0.7874 0.5842)
					(thickness 0.1524)
				)
				(justify left)
			)
		)
		(property "Value" ""
			(at 0 0 0)
			(layer "F.Fab")
			(effects
				(font
					(size 1.27 1.27)
				)
			)
		)
		(duplicate_pad_numbers_are_jumpers no)
		(pad "1" smd rect
			(at -3.81 -5.715 270)
			(size 0.762 1.27)
			(layers "F.Cu" "F.Mask" "F.Paste")
			(net "GND")
		)
		(pad "2" smd rect
			(at -3.81 -4.445 270)
			(size 0.762 1.27)
			(layers "F.Cu" "F.Mask" "F.Paste")
			(net "FM_FORCE_ALL_PWRON_ON")
		)
		(pad "3" smd rect
			(at -3.81 -3.175 270)
			(size 0.762 1.27)
			(layers "F.Cu" "F.Mask" "F.Paste")
			(net "GND")
		)
		(pad "4" smd rect
			(at -3.81 -1.905 270)
			(size 0.762 1.27)
			(layers "F.Cu" "F.Mask" "F.Paste")
			(net "PU_BIOS_USB_RECOVERY")
		)
		(pad "5" smd rect
			(at -3.81 -0.635 270)
			(size 0.762 1.27)
			(layers "F.Cu" "F.Mask" "F.Paste")
			(net "PU_FPGA_DEBUG_SW_SPARE")
		)
		(pad "6" smd rect
			(at -3.81 0.635 270)
			(size 0.762 1.27)
			(layers "F.Cu" "F.Mask" "F.Paste")
			(net "PD_BIOS_DEBUG_MODE")
		)
		(pad "7" smd rect
			(at -3.81 1.905 270)
			(size 0.762 1.27)
			(layers "F.Cu" "F.Mask" "F.Paste")
			(net "PRSNT_CPU0_N")
		)
		(pad "8" smd rect
			(at -3.81 3.175 270)
			(size 0.762 1.27)
			(layers "F.Cu" "F.Mask" "F.Paste")
			(net "PRSNT_CPU1_N")
		)
		(pad "9" smd rect
			(at -3.81 4.445 270)
			(size 0.762 1.27)
			(layers "F.Cu" "F.Mask" "F.Paste")
			(net "GND")
		)
		(pad "10" smd rect
			(at -3.81 5.715 270)
			(size 0.762 1.27)
			(layers "F.Cu" "F.Mask" "F.Paste")
			(net "PU_FPGA_DEBUG_LED_CTRL")
		)
		(pad "11" smd rect
			(at 3.81 -5.715 270)
			(size 0.762 1.27)
			(layers "F.Cu" "F.Mask" "F.Paste")
			(net "FM_SPD_CPU0_SWITCH_CTRL_N")
		)
		(pad "12" smd rect
			(at 3.81 -4.445 270)
			(size 0.762 1.27)
			(layers "F.Cu" "F.Mask" "F.Paste")
			(net "FM_FORCE_ALL_PWRON")
		)
		(pad "13" smd rect
			(at 3.81 -3.175 270)
			(size 0.762 1.27)
			(layers "F.Cu" "F.Mask" "F.Paste")
			(net "BMC_JTAG_SEL")
		)
		(pad "14" smd rect
			(at 3.81 -1.905 270)
			(size 0.762 1.27)
			(layers "F.Cu" "F.Mask" "F.Paste")
			(net "FM_BIOS_USB_RECOVERY")
		)
		(pad "15" smd rect
			(at 3.81 -0.635 270)
			(size 0.762 1.27)
			(layers "F.Cu" "F.Mask" "F.Paste")
			(net "FPGA_DEBUG_SW_SPARE")
		)
		(pad "16" smd rect
			(at 3.81 0.635 270)
			(size 0.762 1.27)
			(layers "F.Cu" "F.Mask" "F.Paste")
			(net "BIOS_DEBUG_MODE")
		)
		(pad "17" smd rect
			(at 3.81 1.905 270)
			(size 0.762 1.27)
			(layers "F.Cu" "F.Mask" "F.Paste")
			(net "FM_PRSNT_CPU0_N")
		)
		(pad "18" smd rect
			(at 3.81 3.175 270)
			(size 0.762 1.27)
			(layers "F.Cu" "F.Mask" "F.Paste")
			(net "FM_PRSNT_CPU1_N")
		)
		(pad "19" smd rect
			(at 3.81 4.445 270)
			(size 0.762 1.27)
			(layers "F.Cu" "F.Mask" "F.Paste")
			(net "FM_PASSWORD_CLEAR_N")
		)
		(pad "20" smd rect
			(at 3.81 5.715 270)
			(size 0.762 1.27)
			(layers "F.Cu" "F.Mask" "F.Paste")
			(net "FPGA_DEBUG_LED_CTRL")
		)
	)
)
